#ISCELL
  mstr_misc dns *
  *
#ISCELL
  pure_quanta quanta_title_block_c *
  *
#CELL
  pure_quanta q_res *
  page334_i123
#CELL
  pure_quanta q_res *
  page334_i124
#ISCELL
  pure_quanta_power universal_power *
  page334_i125
#ISCELL
  pure_quanta_power universal_gnd *
  page334_i126
#CELL
  pure_quanta q_res *
  page334_i127
#ISCELL
  pure_quanta_power universal_gnd *
  page334_i137
#ISCELL
  pure_quanta_power universal_gnd *
  page334_i138
#CELL
  pure_quanta q_res *
  page334_i139
#CELL
  pure_quanta q_res *
  page334_i140
#ISCELL
  standard offpage *
  page334_i146
#CELL
  pure_quanta q_cap *
  page334_i148
#ISCELL
  pure_quanta_power universal_gnd *
  page334_i149
#CELL
  pure_quanta 74lvc2g17gw *
  page334_i153
#ISCELL
  pure_quanta_power universal_power *
  page334_i154
#ISCELL
  pure_quanta_power universal_gnd *
  page334_i16
#ISCELL
  standard offpage *
  page334_i161
#CELL
  pure_quanta q_res *
  page334_i162
#ISCELL
  pure_quanta_power universal_power *
  page334_i163
#CELL
  pure_quanta q_res *
  page334_i164
#CELL
  pure_quanta q_res *
  page334_i165
#ISCELL
  pure_quanta_power universal_gnd *
  page334_i166
#ISCELL
  pure_quanta_power universal_power *
  page334_i167
#CELL
  pure_quanta q_res *
  page334_i168
#ISCELL
  standard offpage *
  page334_i169
#CELL
  pure_quanta q_res *
  page334_i170
#ISCELL
  pure_quanta_power universal_gnd *
  page334_i171
#ISCELL
  standard offpage *
  page334_i172
#CELL
  pure_quanta 74lvc2g17gw *
  page334_i173
#ISCELL
  pure_quanta_power universal_power *
  page334_i174
#CELL
  pure_quanta q_cap *
  page334_i175
#ISCELL
  pure_quanta_power universal_gnd *
  page334_i176
#ISCELL
  pure_quanta_power universal_gnd *
  page334_i177
#ISCELL
  pure_quanta_power universal_gnd *
  page334_i178
#ISCELL
  standard offpage *
  page334_i179
#ISCELL
  standard offpage *
  page334_i18
#CELL
  pure_quanta q_res *
  page334_i180
#CELL
  pure_quanta q_res *
  page334_i181
#ISCELL
  standard offpage *
  page334_i182
#CELL
  pure_quanta q_res *
  page334_i183
#CELL
  pure_quanta q_res *
  page334_i184
#ISCELL
  pure_quanta_power universal_gnd *
  page334_i185
#ISCELL
  pure_quanta_power universal_power *
  page334_i186
#CELL
  pure_quanta q_res *
  page334_i187
#CELL
  pure_quanta q_res *
  page334_i188
#ISCELL
  pure_quanta_power universal_gnd *
  page334_i189
#ISCELL
  standard offpage *
  page334_i190
#ISCELL
  pure_quanta_power universal_power *
  page334_i191
#CELL
  pure_quanta q_res *
  page334_i192
#CELL
  pure_quanta q_res *
  page334_i193
#ISCELL
  standard offpage *
  page334_i194
#CELL
  pure_quanta q_res *
  page334_i195
#ISCELL
  pure_quanta_power universal_gnd *
  page334_i196
#ISCELL
  standard offpage *
  page334_i197
#ISCELL
  standard offpage *
  page334_i198
#ISCELL
  pure_quanta_power universal_power *
  page334_i20
#CELL
  pure_quanta 74lvc2g17gw *
  page334_i26
#ISCELL
  pure_quanta_power universal_gnd *
  page334_i27
#ISCELL
  pure_quanta_power universal_gnd *
  page334_i28
#CELL
  pure_quanta q_cap *
  page334_i29
#ISCELL
  pure_quanta_power universal_power *
  page334_i30
#CELL
  pure_quanta q_res *
  page334_i62
#ISCELL
  standard offpage *
  page334_i67
#CELL
  pure_quanta q_res *
  page334_i95
